# S9S_MB_2U (Grand Teton) — schematic netlist excerpt (pin names and nets, part order shuffled) for the footprints in the layout excerpt that follows; sources: Cadence DE-HDL packaged netlist, KiCad conversion of 03242023_DA0F0TMBIJ0_F0T_Motherboard_J_brd_V01_OCP.brd

Q125  MOSFET_NCH_DUAL  PJT138K EMPTY  pkg SOT363XD  page 242
  S1  = GND
  G1  = P12V_SCM_EN_R
  D2  = P12V_SCM_UV_R
  S2  = GND
  G2  = P12V_SCM_EN_G
  D1  = P12V_SCM_EN_G

R4076  Q_RES  0 5% CHIP  pkg 0402LF  page 212 : A = CLK_GEN2_GPU_FPGA_OE_OR_N ; B = CLK_GEN2_GPU_OE_N

(kicad_pcb
	(version 20260206)
	(generator "pcbnew")
	(generator_version "10.0")
	(general
		(thickness 1.6)
		(legacy_teardrops no)
	)
	(paper "A4")
	(title_block
		(title "03242023_DA0F0TMBIJ0_F0T_Motherboard_J_brd_V01_OCP.brd")
		(comment 1 "Grand Teton / footprints 3204-3205 of 6105")
	)
	(layers
		(0 "F.Cu" signal "TOP")
		(4 "In1.Cu" signal "GND")
		(6 "In2.Cu" signal "IN1")
		(8 "In3.Cu" signal "GND1")
		(10 "In4.Cu" signal "IN2")
		(12 "In5.Cu" signal "GND2")
		(14 "In6.Cu" signal "IN3")
		(16 "In7.Cu" signal "GND3")
		(18 "In8.Cu" signal "VCC")
		(20 "In9.Cu" signal "VCC1")
		(22 "In10.Cu" signal "GND4")
		(24 "In11.Cu" signal "IN4")
		(26 "In12.Cu" signal "GND5")
		(28 "In13.Cu" signal "IN5")
		(30 "In14.Cu" signal "GND6")
		(32 "In15.Cu" signal "IN6")
		(34 "In16.Cu" signal "GND7")
		(2 "B.Cu" signal "BOTTOM")
		(9 "F.Adhes" user "F.Adhesive")
		(11 "B.Adhes" user "B.Adhesive")
		(13 "F.Paste" user "Package Geometry/Pastemask Top")
		(15 "B.Paste" user "Package Geometry/Pastemask Bottom")
		(5 "F.SilkS" user "Ref Des/Silkscreen Top")
		(7 "B.SilkS" user "Ref Des/Silkscreen Bottom")
		(1 "F.Mask" user "Board Geometry/Soldermask Top")
		(3 "B.Mask" user "Board Geometry/Soldermask Bottom")
		(17 "Dwgs.User" user "User.Drawings")
		(19 "Cmts.User" user "User.Comments")
		(21 "Eco1.User" user "User.Eco1")
		(23 "Eco2.User" user "User.Eco2")
		(25 "Edge.Cuts" user "Board Geometry/Outline")
		(27 "Margin" user)
		(31 "F.CrtYd" user "Package Geometry/Place Bound Top")
		(29 "B.CrtYd" user "Package Geometry/Place Bound Bottom")
		(35 "F.Fab" user "Ref Des/Assembly Top")
		(33 "B.Fab" user "Ref Des/Assembly Bottom")
	)
	(footprint ""
		(layer "F.Cu")
		(at 232.911396 -245.411498 90)
		(property "Reference" "R4076"
			(at 0 0 90)
			(layer "F.SilkS")
			(hide yes)
			(effects
				(font
					(size 1.27 1.27)
				)
			)
		)
		(property "Value" ""
			(at 0 0 90)
			(layer "F.Fab")
			(effects
				(font
					(size 1.27 1.27)
				)
			)
		)
		(duplicate_pad_numbers_are_jumpers no)
		(fp_line
			(start 0.7874 -0.4064)
			(end 0.7874 0.4064)
			(stroke
				(width 0.1524)
				(type default)
			)
			(layer "F.SilkS")
		)
		(fp_line
			(start -0.7874 -0.4064)
			(end 0.7874 -0.4064)
			(stroke
				(width 0.1524)
				(type default)
			)
			(layer "F.SilkS")
		)
		(fp_line
			(start 0.7874 0.4064)
			(end -0.7874 0.4064)
			(stroke
				(width 0.1524)
				(type default)
			)
			(layer "F.SilkS")
		)
		(fp_line
			(start -0.7874 0.4064)
			(end -0.7874 -0.4064)
			(stroke
				(width 0.1524)
				(type default)
			)
			(layer "F.SilkS")
		)
		(fp_line
			(start -0.12065 -0.305054)
			(end -0.12065 -0.2794)
			(stroke
				(width 0.1)
				(type default)
			)
			(layer "F.Fab")
		)
		(fp_line
			(start -0.67945 -0.305054)
			(end -0.12065 -0.305054)
			(stroke
				(width 0.1)
				(type default)
			)
			(layer "F.Fab")
		)
		(fp_line
			(start 0.67945 -0.3048)
			(end 0.67945 0.3048)
			(stroke
				(width 0.1)
				(type default)
			)
			(layer "F.Fab")
		)
		(fp_line
			(start 0.12065 -0.3048)
			(end 0.67945 -0.3048)
			(stroke
				(width 0.1)
				(type default)
			)
			(layer "F.Fab")
		)
		(fp_line
			(start 0.12065 -0.2794)
			(end 0.12065 -0.3048)
			(stroke
				(width 0.1)
				(type default)
			)
			(layer "F.Fab")
		)
		(fp_line
			(start -0.12065 -0.2794)
			(end 0.12065 -0.2794)
			(stroke
				(width 0.1)
				(type default)
			)
			(layer "F.Fab")
		)
		(fp_line
			(start 0.120396 0.2794)
			(end -0.12065 0.2794)
			(stroke
				(width 0.1)
				(type default)
			)
			(layer "F.Fab")
		)
		(fp_line
			(start -0.12065 0.2794)
			(end -0.12065 0.3048)
			(stroke
				(width 0.1)
				(type default)
			)
			(layer "F.Fab")
		)
		(fp_line
			(start 0.67945 0.3048)
			(end 0.120396 0.3048)
			(stroke
				(width 0.1)
				(type default)
			)
			(layer "F.Fab")
		)
		(fp_line
			(start 0.120396 0.3048)
			(end 0.120396 0.2794)
			(stroke
				(width 0.1)
				(type default)
			)
			(layer "F.Fab")
		)
		(fp_line
			(start -0.12065 0.3048)
			(end -0.67945 0.3048)
			(stroke
				(width 0.1)
				(type default)
			)
			(layer "F.Fab")
		)
		(fp_line
			(start -0.67945 0.3048)
			(end -0.67945 -0.305054)
			(stroke
				(width 0.1)
				(type default)
			)
			(layer "F.Fab")
		)
		(pad "1" smd circle
			(at -0.40005 0 90)
			(size 0 0)
			(layers "F.Cu" "F.Mask" "F.Paste")
			(net "CLK_GEN2_GPU_FPGA_OE_OR_N")
		)
		(pad "2" smd circle
			(at 0.40005 0 90)
			(size 0 0)
			(layers "F.Cu" "F.Mask" "F.Paste")
			(net "CLK_GEN2_GPU_OE_N")
		)
	)
	(footprint ""
		(layer "F.Cu")
		(at 194.30619 -43.199558 180)
		(property "Reference" "Q125"
			(at 5.05206 1.580388 0)
			(unlocked yes)
			(layer "F.SilkS")
			(effects
				(font
					(size 0.7874 0.5842)
					(thickness 0.1524)
				)
				(justify left)
			)
		)
		(property "Value" ""
			(at 0 0 180)
			(layer "F.Fab")
			(effects
				(font
					(size 1.27 1.27)
				)
			)
		)
		(duplicate_pad_numbers_are_jumpers no)
		(fp_line
			(start 1.332738 1.100074)
			(end -1.332738 1.100074)
			(stroke
				(width 0.1524)
				(type default)
			)
			(layer "F.SilkS")
		)
		(fp_line
			(start 1.332738 -1.100074)
			(end 1.332738 1.100074)
			(stroke
				(width 0.1524)
				(type default)
			)
			(layer "F.SilkS")
		)
		(fp_line
			(start 0.4826 -1.100074)
			(end 1.332738 -1.100074)
			(stroke
				(width 0.1524)
				(type default)
			)
			(layer "F.SilkS")
		)
		(fp_line
			(start 0 -0.541274)
			(end 0.4826 -1.100074)
			(stroke
				(width 0.1524)
				(type default)
			)
			(layer "F.SilkS")
		)
		(fp_line
			(start -0.4826 -1.100074)
			(end 0 -0.541274)
			(stroke
				(width 0.1524)
				(type default)
			)
			(layer "F.SilkS")
		)
		(fp_line
			(start -1.332738 1.100074)
			(end -1.332738 -1.100074)
			(stroke
				(width 0.1524)
				(type default)
			)
			(layer "F.SilkS")
		)
		(fp_line
			(start -1.332738 -1.100074)
			(end -0.4826 -1.100074)
			(stroke
				(width 0.1524)
				(type default)
			)
			(layer "F.SilkS")
		)
		(fp_poly
			(pts
				(xy -1.928114 -1.29413) (xy -1.495552 -0.639064) (xy -2.279142 -0.686054)
			)
			(stroke
				(width 0)
				(type default)
			)
			(fill yes)
			(layer "F.SilkS")
		)
		(fp_line
			(start 0.674878 1.100074)
			(end -0.674878 1.100074)
			(stroke
				(width 0.1)
				(type default)
			)
			(layer "F.Fab")
		)
		(fp_line
			(start 0.674878 -1.100074)
			(end 0.674878 1.100074)
			(stroke
				(width 0.1)
				(type default)
			)
			(layer "F.Fab")
		)
		(fp_line
			(start -0.674878 1.100074)
			(end -0.674878 -1.100074)
			(stroke
				(width 0.1)
				(type default)
			)
			(layer "F.Fab")
		)
		(fp_line
			(start -0.674878 -1.100074)
			(end 0.674878 -1.100074)
			(stroke
				(width 0.1)
				(type default)
			)
			(layer "F.Fab")
		)
		(fp_poly
			(pts
				(xy -2.2352 -0.298958) (xy -2.2352 -1.001014) (xy -1.533144 -0.649986)
			)
			(stroke
				(width 0)
				(type default)
			)
			(fill yes)
			(layer "F.Fab")
		)
		(pad "1" smd rect
			(at -0.94996 -0.649986 270)
			(size 0.4318 0.508)
			(layers "F.Cu" "F.Mask" "F.Paste")
			(net "GND")
		)
		(pad "2" smd rect
			(at -0.94996 0 270)
			(size 0.4318 0.508)
			(layers "F.Cu" "F.Mask" "F.Paste")
			(net "P12V_SCM_EN_R")
		)
		(pad "3" smd rect
			(at -0.94996 0.649986 270)
			(size 0.4318 0.508)
			(layers "F.Cu" "F.Mask" "F.Paste")
			(net "P12V_SCM_UV_R")
		)
		(pad "4" smd rect
			(at 0.94996 0.649986 270)
			(size 0.4318 0.508)
			(layers "F.Cu" "F.Mask" "F.Paste")
			(net "GND")
		)
		(pad "5" smd rect
			(at 0.94996 0 270)
			(size 0.4318 0.508)
			(layers "F.Cu" "F.Mask" "F.Paste")
			(net "P12V_SCM_EN_G")
		)
		(pad "6" smd rect
			(at 0.94996 -0.649986 270)
			(size 0.4318 0.508)
			(layers "F.Cu" "F.Mask" "F.Paste")
			(net "P12V_SCM_EN_G")
		)
	)
)
